# S9S_MB_2U (Grand Teton) — schematic netlist excerpt (pin names and nets, part order shuffled) for the footprints in the layout excerpt that follows; sources: Cadence DE-HDL packaged netlist, KiCad conversion of 03242023_DA0F0TMBIJ0_F0T_Motherboard_J_brd_V01_OCP.brd

C743  Q_CAP_DIFFBUS  DIFF BUS_0.22UF 6.3V 20% X6S  pkg C0201  page 176 : \1\ = P5E_CPU1_PE2_TX_C_DP<15> ; \2\ = P5E_CPU1_PE2_TX_DP<15>
C1105  Q_CAP_DIFFBUS  DIFF BUS_0.22UF 6.3V 20% X6S  pkg C0201  page 181 : \1\ = P3E_PCH_M2_TX_DN<0> ; \2\ = P3E_PCH_M2_TX_C_DN<0>

(kicad_pcb
	(version 20260206)
	(generator "pcbnew")
	(generator_version "10.0")
	(general
		(thickness 1.6)
		(legacy_teardrops no)
	)
	(paper "A4")
	(title_block
		(title "03242023_DA0F0TMBIJ0_F0T_Motherboard_J_brd_V01_OCP.brd")
		(comment 1 "Grand Teton / footprints 1066-1067 of 6105")
	)
	(layers
		(0 "F.Cu" signal "TOP")
		(4 "In1.Cu" signal "GND")
		(6 "In2.Cu" signal "IN1")
		(8 "In3.Cu" signal "GND1")
		(10 "In4.Cu" signal "IN2")
		(12 "In5.Cu" signal "GND2")
		(14 "In6.Cu" signal "IN3")
		(16 "In7.Cu" signal "GND3")
		(18 "In8.Cu" signal "VCC")
		(20 "In9.Cu" signal "VCC1")
		(22 "In10.Cu" signal "GND4")
		(24 "In11.Cu" signal "IN4")
		(26 "In12.Cu" signal "GND5")
		(28 "In13.Cu" signal "IN5")
		(30 "In14.Cu" signal "GND6")
		(32 "In15.Cu" signal "IN6")
		(34 "In16.Cu" signal "GND7")
		(2 "B.Cu" signal "BOTTOM")
		(9 "F.Adhes" user "F.Adhesive")
		(11 "B.Adhes" user "B.Adhesive")
		(13 "F.Paste" user "Package Geometry/Pastemask Top")
		(15 "B.Paste" user "Package Geometry/Pastemask Bottom")
		(5 "F.SilkS" user "Ref Des/Silkscreen Top")
		(7 "B.SilkS" user "Ref Des/Silkscreen Bottom")
		(1 "F.Mask" user "Board Geometry/Soldermask Top")
		(3 "B.Mask" user "Board Geometry/Soldermask Bottom")
		(17 "Dwgs.User" user "User.Drawings")
		(19 "Cmts.User" user "User.Comments")
		(21 "Eco1.User" user "User.Eco1")
		(23 "Eco2.User" user "User.Eco2")
		(25 "Edge.Cuts" user "Board Geometry/Outline")
		(27 "Margin" user)
		(31 "F.CrtYd" user "Package Geometry/Place Bound Top")
		(29 "B.CrtYd" user "Package Geometry/Place Bound Bottom")
		(35 "F.Fab" user "Ref Des/Assembly Top")
		(33 "B.Fab" user "Ref Des/Assembly Bottom")
	)
	(footprint ""
		(layer "F.Cu")
		(at 180.528468 -53.065934 180)
		(property "Reference" "C1105"
			(at 0 0 180)
			(layer "F.SilkS")
			(hide yes)
			(effects
				(font
					(size 1.27 1.27)
				)
			)
		)
		(property "Value" ""
			(at 0 0 180)
			(layer "F.Fab")
			(effects
				(font
					(size 1.27 1.27)
				)
			)
		)
		(duplicate_pad_numbers_are_jumpers no)
		(fp_line
			(start 0.299974 0.150114)
			(end -0.299974 0.150114)
			(stroke
				(width 0.1)
				(type default)
			)
			(layer "F.Fab")
		)
		(fp_line
			(start 0.299974 -0.150114)
			(end 0.299974 0.150114)
			(stroke
				(width 0.1)
				(type default)
			)
			(layer "F.Fab")
		)
		(fp_line
			(start -0.299974 0.150114)
			(end -0.299974 -0.150114)
			(stroke
				(width 0.1)
				(type default)
			)
			(layer "F.Fab")
		)
		(fp_line
			(start -0.299974 -0.150114)
			(end 0.299974 -0.150114)
			(stroke
				(width 0.1)
				(type default)
			)
			(layer "F.Fab")
		)
		(pad "1" smd rect
			(at -0.2667 0 180)
			(size 0.3048 0.381)
			(layers "F.Cu" "F.Mask" "F.Paste")
			(net "P3E_PCH_M2_TX_DN<0>")
		)
		(pad "2" smd rect
			(at 0.2667 0 180)
			(size 0.3048 0.381)
			(layers "F.Cu" "F.Mask" "F.Paste")
			(net "P3E_PCH_M2_TX_C_DN<0>")
		)
		(zone
			(layer "In1.Cu")
			(hatch none 0.5)
			(connect_pads
				(clearance 0)
			)
			(min_thickness 0.25)
			(keepout
				(tracks not_allowed)
				(vias allowed)
				(pads allowed)
				(copperpour not_allowed)
				(footprints allowed)
			)
			(placement
				(enabled no)
				(sheetname "")
			)
			(fill
				(thermal_gap 0.5)
				(thermal_bridge_width 0.5)
				(island_removal_mode 0)
			)
			(polygon
				(pts
					(arc
						(start 180.388768 -53.307234)
						(mid 180.44265 -53.284916)
						(end 180.464968 -53.231034)
					)
					(arc
						(start 180.464968 -52.900834)
						(mid 180.44265 -52.846952)
						(end 180.388768 -52.824634)
					)
					(arc
						(start 180.134768 -52.824634)
						(mid 180.080886 -52.846952)
						(end 180.058568 -52.900834)
					)
					(arc
						(start 180.058568 -53.231034)
						(mid 180.080886 -53.284916)
						(end 180.134768 -53.307234)
					)
				)
			)
		)
		(zone
			(layer "In1.Cu")
			(hatch none 0.5)
			(connect_pads
				(clearance 0)
			)
			(min_thickness 0.25)
			(keepout
				(tracks not_allowed)
				(vias allowed)
				(pads allowed)
				(copperpour not_allowed)
				(footprints allowed)
			)
			(placement
				(enabled no)
				(sheetname "")
			)
			(fill
				(thermal_gap 0.5)
				(thermal_bridge_width 0.5)
				(island_removal_mode 0)
			)
			(polygon
				(pts
					(arc
						(start 180.922168 -53.307234)
						(mid 180.97605 -53.284916)
						(end 180.998368 -53.231034)
					)
					(arc
						(start 180.998368 -52.900834)
						(mid 180.97605 -52.846952)
						(end 180.922168 -52.824634)
					)
					(arc
						(start 180.668168 -52.824634)
						(mid 180.614286 -52.846952)
						(end 180.591968 -52.900834)
					)
					(arc
						(start 180.591968 -53.231034)
						(mid 180.614286 -53.284916)
						(end 180.668168 -53.307234)
					)
				)
			)
		)
	)
	(footprint ""
		(layer "F.Cu")
		(at 120.129554 -402.371052 -90)
		(property "Reference" "C743"
			(at 0 0 270)
			(layer "F.SilkS")
			(hide yes)
			(effects
				(font
					(size 1.27 1.27)
				)
			)
		)
		(property "Value" ""
			(at 0 0 270)
			(layer "F.Fab")
			(effects
				(font
					(size 1.27 1.27)
				)
			)
		)
		(duplicate_pad_numbers_are_jumpers no)
		(fp_line
			(start -0.299974 0.150114)
			(end -0.299974 -0.150114)
			(stroke
				(width 0.1)
				(type default)
			)
			(layer "F.Fab")
		)
		(fp_line
			(start 0.299974 0.150114)
			(end -0.299974 0.150114)
			(stroke
				(width 0.1)
				(type default)
			)
			(layer "F.Fab")
		)
		(fp_line
			(start -0.299974 -0.150114)
			(end 0.299974 -0.150114)
			(stroke
				(width 0.1)
				(type default)
			)
			(layer "F.Fab")
		)
		(fp_line
			(start 0.299974 -0.150114)
			(end 0.299974 0.150114)
			(stroke
				(width 0.1)
				(type default)
			)
			(layer "F.Fab")
		)
		(pad "1" smd rect
			(at -0.2667 0 270)
			(size 0.3048 0.381)
			(layers "F.Cu" "F.Mask" "F.Paste")
			(net "P5E_CPU1_PE2_TX_C_DP<15>")
		)
		(pad "2" smd rect
			(at 0.2667 0 270)
			(size 0.3048 0.381)
			(layers "F.Cu" "F.Mask" "F.Paste")
			(net "P5E_CPU1_PE2_TX_DP<15>")
		)
	)
)
